# T6G (Grand Teton) — schematic netlist excerpt (pin names and nets, part order shuffled) for the footprints in the layout excerpt that follows; sources: Cadence DE-HDL packaged netlist, KiCad conversion of 04192023_DAF0TMB3IC0_F0TG_MB_C_brd_V02_OCP.brd

C1859  Q_CAP  0.1UF 25V 10% X7R  pkg 0402  page 247 : A = P3V3_AUX ; B = GND
PR517  Q_RES  1.5 1% EMPTY  pkg 0402LF  page 220 : A = SW_PVDDCR_CPU1_P1_SW5_RC ; B = GND

(kicad_pcb
	(version 20260206)
	(generator "pcbnew")
	(generator_version "10.0")
	(general
		(thickness 1.6)
		(legacy_teardrops no)
	)
	(paper "A4")
	(title_block
		(title "04192023_DAF0TMB3IC0_F0TG_MB_C_brd_V02_OCP.brd")
		(comment 1 "Grand Teton / footprints 668-669 of 8354")
	)
	(layers
		(0 "F.Cu" signal "TOP")
		(4 "In1.Cu" signal "GND")
		(6 "In2.Cu" signal "IN1")
		(8 "In3.Cu" signal "GND1")
		(10 "In4.Cu" signal "IN2")
		(12 "In5.Cu" signal "GND2")
		(14 "In6.Cu" signal "IN3")
		(16 "In7.Cu" signal "GND3")
		(18 "In8.Cu" signal "VCC")
		(20 "In9.Cu" signal "VCC1")
		(22 "In10.Cu" signal "GND4")
		(24 "In11.Cu" signal "IN4")
		(26 "In12.Cu" signal "GND5")
		(28 "In13.Cu" signal "IN5")
		(30 "In14.Cu" signal "GND6")
		(32 "In15.Cu" signal "IN6")
		(34 "In16.Cu" signal "GND7")
		(2 "B.Cu" signal "BOTTOM")
		(9 "F.Adhes" user "F.Adhesive")
		(11 "B.Adhes" user "B.Adhesive")
		(13 "F.Paste" user "Package Geometry/Pastemask Top")
		(15 "B.Paste" user "Package Geometry/Pastemask Bottom")
		(5 "F.SilkS" user "Ref Des/Silkscreen Top")
		(7 "B.SilkS" user "Ref Des/Silkscreen Bottom")
		(1 "F.Mask" user "Board Geometry/Soldermask Top")
		(3 "B.Mask" user "Board Geometry/Soldermask Bottom")
		(17 "Dwgs.User" user "User.Drawings")
		(19 "Cmts.User" user "User.Comments")
		(21 "Eco1.User" user "User.Eco1")
		(23 "Eco2.User" user "User.Eco2")
		(25 "Edge.Cuts" user "Board Geometry/Outline")
		(27 "Margin" user)
		(31 "F.CrtYd" user "Package Geometry/Place Bound Top")
		(29 "B.CrtYd" user "Package Geometry/Place Bound Bottom")
		(35 "F.Fab" user "Ref Des/Assembly Top")
		(33 "B.Fab" user "Ref Des/Assembly Bottom")
	)
	(footprint ""
		(layer "F.Cu")
		(at 143.88084 -40.403526 90)
		(property "Reference" "C1859"
			(at 0 0 90)
			(layer "F.SilkS")
			(hide yes)
			(effects
				(font
					(size 1.27 1.27)
				)
			)
		)
		(property "Value" ""
			(at 0 0 90)
			(layer "F.Fab")
			(effects
				(font
					(size 1.27 1.27)
				)
			)
		)
		(duplicate_pad_numbers_are_jumpers no)
		(fp_line
			(start 0.7874 -0.4064)
			(end 0.7874 0.4064)
			(stroke
				(width 0.1524)
				(type default)
			)
			(layer "F.SilkS")
		)
		(fp_line
			(start -0.7874 -0.4064)
			(end 0.7874 -0.4064)
			(stroke
				(width 0.1524)
				(type default)
			)
			(layer "F.SilkS")
		)
		(fp_line
			(start 0.7874 0.4064)
			(end -0.7874 0.4064)
			(stroke
				(width 0.1524)
				(type default)
			)
			(layer "F.SilkS")
		)
		(fp_line
			(start -0.7874 0.4064)
			(end -0.7874 -0.4064)
			(stroke
				(width 0.1524)
				(type default)
			)
			(layer "F.SilkS")
		)
		(fp_line
			(start -0.12065 -0.305054)
			(end -0.12065 -0.2794)
			(stroke
				(width 0.1)
				(type default)
			)
			(layer "F.Fab")
		)
		(fp_line
			(start -0.67945 -0.305054)
			(end -0.12065 -0.305054)
			(stroke
				(width 0.1)
				(type default)
			)
			(layer "F.Fab")
		)
		(fp_line
			(start 0.67945 -0.3048)
			(end 0.67945 0.3048)
			(stroke
				(width 0.1)
				(type default)
			)
			(layer "F.Fab")
		)
		(fp_line
			(start 0.12065 -0.3048)
			(end 0.67945 -0.3048)
			(stroke
				(width 0.1)
				(type default)
			)
			(layer "F.Fab")
		)
		(fp_line
			(start 0.12065 -0.2794)
			(end 0.12065 -0.3048)
			(stroke
				(width 0.1)
				(type default)
			)
			(layer "F.Fab")
		)
		(fp_line
			(start -0.12065 -0.2794)
			(end 0.12065 -0.2794)
			(stroke
				(width 0.1)
				(type default)
			)
			(layer "F.Fab")
		)
		(fp_line
			(start 0.120396 0.2794)
			(end -0.12065 0.2794)
			(stroke
				(width 0.1)
				(type default)
			)
			(layer "F.Fab")
		)
		(fp_line
			(start -0.12065 0.2794)
			(end -0.12065 0.3048)
			(stroke
				(width 0.1)
				(type default)
			)
			(layer "F.Fab")
		)
		(fp_line
			(start 0.67945 0.3048)
			(end 0.120396 0.3048)
			(stroke
				(width 0.1)
				(type default)
			)
			(layer "F.Fab")
		)
		(fp_line
			(start 0.120396 0.3048)
			(end 0.120396 0.2794)
			(stroke
				(width 0.1)
				(type default)
			)
			(layer "F.Fab")
		)
		(fp_line
			(start -0.12065 0.3048)
			(end -0.67945 0.3048)
			(stroke
				(width 0.1)
				(type default)
			)
			(layer "F.Fab")
		)
		(fp_line
			(start -0.67945 0.3048)
			(end -0.67945 -0.305054)
			(stroke
				(width 0.1)
				(type default)
			)
			(layer "F.Fab")
		)
		(pad "1" smd circle
			(at -0.40005 0 90)
			(size 0 0)
			(layers "F.Cu" "F.Mask" "F.Paste")
			(net "P3V3_AUX")
		)
		(pad "2" smd circle
			(at 0.40005 0 90)
			(size 0 0)
			(layers "F.Cu" "F.Mask" "F.Paste")
			(net "GND")
		)
	)
	(footprint ""
		(layer "F.Cu")
		(at 91.776296 -333.29499 90)
		(property "Reference" "PR517"
			(at 0 0 90)
			(layer "F.SilkS")
			(hide yes)
			(effects
				(font
					(size 1.27 1.27)
				)
			)
		)
		(property "Value" ""
			(at 0 0 90)
			(layer "F.Fab")
			(effects
				(font
					(size 1.27 1.27)
				)
			)
		)
		(duplicate_pad_numbers_are_jumpers no)
		(fp_line
			(start 0.7874 -0.4064)
			(end 0.7874 0.4064)
			(stroke
				(width 0.1524)
				(type default)
			)
			(layer "F.SilkS")
		)
		(fp_line
			(start -0.7874 -0.4064)
			(end 0.7874 -0.4064)
			(stroke
				(width 0.1524)
				(type default)
			)
			(layer "F.SilkS")
		)
		(fp_line
			(start 0.7874 0.4064)
			(end -0.7874 0.4064)
			(stroke
				(width 0.1524)
				(type default)
			)
			(layer "F.SilkS")
		)
		(fp_line
			(start -0.7874 0.4064)
			(end -0.7874 -0.4064)
			(stroke
				(width 0.1524)
				(type default)
			)
			(layer "F.SilkS")
		)
		(fp_line
			(start -0.12065 -0.305054)
			(end -0.12065 -0.2794)
			(stroke
				(width 0.1)
				(type default)
			)
			(layer "F.Fab")
		)
		(fp_line
			(start -0.67945 -0.305054)
			(end -0.12065 -0.305054)
			(stroke
				(width 0.1)
				(type default)
			)
			(layer "F.Fab")
		)
		(fp_line
			(start 0.67945 -0.3048)
			(end 0.67945 0.3048)
			(stroke
				(width 0.1)
				(type default)
			)
			(layer "F.Fab")
		)
		(fp_line
			(start 0.12065 -0.3048)
			(end 0.67945 -0.3048)
			(stroke
				(width 0.1)
				(type default)
			)
			(layer "F.Fab")
		)
		(fp_line
			(start 0.12065 -0.2794)
			(end 0.12065 -0.3048)
			(stroke
				(width 0.1)
				(type default)
			)
			(layer "F.Fab")
		)
		(fp_line
			(start -0.12065 -0.2794)
			(end 0.12065 -0.2794)
			(stroke
				(width 0.1)
				(type default)
			)
			(layer "F.Fab")
		)
		(fp_line
			(start 0.120396 0.2794)
			(end -0.12065 0.2794)
			(stroke
				(width 0.1)
				(type default)
			)
			(layer "F.Fab")
		)
		(fp_line
			(start -0.12065 0.2794)
			(end -0.12065 0.3048)
			(stroke
				(width 0.1)
				(type default)
			)
			(layer "F.Fab")
		)
		(fp_line
			(start 0.67945 0.3048)
			(end 0.120396 0.3048)
			(stroke
				(width 0.1)
				(type default)
			)
			(layer "F.Fab")
		)
		(fp_line
			(start 0.120396 0.3048)
			(end 0.120396 0.2794)
			(stroke
				(width 0.1)
				(type default)
			)
			(layer "F.Fab")
		)
		(fp_line
			(start -0.12065 0.3048)
			(end -0.67945 0.3048)
			(stroke
				(width 0.1)
				(type default)
			)
			(layer "F.Fab")
		)
		(fp_line
			(start -0.67945 0.3048)
			(end -0.67945 -0.305054)
			(stroke
				(width 0.1)
				(type default)
			)
			(layer "F.Fab")
		)
		(pad "1" smd circle
			(at -0.40005 0 90)
			(size 0 0)
			(layers "F.Cu" "F.Mask" "F.Paste")
			(net "SW_PVDDCR_CPU1_P1_SW5_RC")
		)
		(pad "2" smd circle
			(at 0.40005 0 90)
			(size 0 0)
			(layers "F.Cu" "F.Mask" "F.Paste")
			(net "GND")
		)
	)
)
